# BASEBOARD_FAB2 (Tioga Pass) — schematic netlist excerpt (pin names and nets, part order shuffled) for the footprints in the layout excerpt that follows; sources: Cadence DE-HDL packaged netlist, KiCad conversion of Wiwynn_Tioga_Pass_MB.brd

C2L3  CAP_A  0.01UF 25V 10% X7R  pkg 0402V  page 173 : A = SATA6G_PCH_PCIE_UP_SATA_RXN<3> ; B = SATA6G_P3_RX_C_DN
C2P1  CAP_A  0.1UF 16V 10% X7R  pkg 0402V  page 170 : A = P3V3_STBY ; B = GND
C9P20  CAP_A  22.0UF 4V 20% X6S  pkg 0603V  page 209 : A = PVCCIN_CPU1 ; B = GND

(kicad_pcb
	(version 20260206)
	(generator "pcbnew")
	(generator_version "10.0")
	(general
		(thickness 1.6)
		(legacy_teardrops no)
	)
	(paper "A4")
	(title_block
		(title "Wiwynn_Tioga_Pass_MB.brd")
		(comment 1 "Tioga Pass / footprints 4640-4642 of 4770")
	)
	(layers
		(0 "F.Cu" signal "TOP")
		(4 "In1.Cu" signal "L2GND")
		(6 "In2.Cu" signal "L3")
		(8 "In3.Cu" signal "L4GND")
		(10 "In4.Cu" signal "L5")
		(12 "In5.Cu" signal "L6GND")
		(14 "In6.Cu" signal "L7VCC")
		(16 "In7.Cu" signal "L8VCC")
		(18 "In8.Cu" signal "L9GND")
		(20 "In9.Cu" signal "L10")
		(22 "In10.Cu" signal "L11GND")
		(24 "In11.Cu" signal "L12")
		(26 "In12.Cu" signal "L13GND")
		(2 "B.Cu" signal "BOTTOM")
		(9 "F.Adhes" user "F.Adhesive")
		(11 "B.Adhes" user "B.Adhesive")
		(13 "F.Paste" user "Package Geometry/Pastemask Top")
		(15 "B.Paste" user "Package Geometry/Pastemask Bottom")
		(5 "F.SilkS" user "Ref Des/Silkscreen Top")
		(7 "B.SilkS" user "Ref Des/Silkscreen Bottom")
		(1 "F.Mask" user "Board Geometry/Soldermask Top")
		(3 "B.Mask" user "Board Geometry/Soldermask Bottom")
		(17 "Dwgs.User" user "User.Drawings")
		(19 "Cmts.User" user "User.Comments")
		(21 "Eco1.User" user "User.Eco1")
		(23 "Eco2.User" user "User.Eco2")
		(25 "Edge.Cuts" user "Board Geometry/Outline")
		(27 "Margin" user)
		(31 "F.CrtYd" user "Package Geometry/Place Bound Top")
		(29 "B.CrtYd" user "Package Geometry/Place Bound Bottom")
		(35 "F.Fab" user "Ref Des/Assembly Top")
		(33 "B.Fab" user "Ref Des/Assembly Bottom")
	)
	(footprint ""
		(layer "B.Cu")
		(at 49.4284 -70.993)
		(property "Reference" "C9P20"
			(at 0 0 0)
			(layer "B.SilkS")
			(hide yes)
			(effects
				(font
					(size 1.27 1.27)
				)
				(justify mirror)
			)
		)
		(property "Value" ""
			(at 0 0 0)
			(layer "B.Fab")
			(effects
				(font
					(size 1.27 1.27)
				)
				(justify mirror)
			)
		)
		(duplicate_pad_numbers_are_jumpers no)
		(fp_poly
			(pts
				(xy 0.4953 -0.2032) (xy -0.4953 -0.2032) (xy -0.4953 1.6002) (xy 0.4953 1.6002)
			)
			(stroke
				(width 0)
				(type default)
			)
			(fill no)
			(layer "B.CrtYd")
		)
		(fp_line
			(start -0.4953 -0.2032)
			(end -0.4953 1.6002)
			(stroke
				(width 0.1)
				(type default)
			)
			(layer "B.Fab")
		)
		(fp_line
			(start -0.4953 1.6002)
			(end 0.4953 1.6002)
			(stroke
				(width 0.1)
				(type default)
			)
			(layer "B.Fab")
		)
		(fp_line
			(start 0.4953 -0.2032)
			(end -0.4953 -0.2032)
			(stroke
				(width 0.1)
				(type default)
			)
			(layer "B.Fab")
		)
		(fp_line
			(start 0.4953 1.6002)
			(end 0.4953 -0.2032)
			(stroke
				(width 0.1)
				(type default)
			)
			(layer "B.Fab")
		)
		(pad "1" smd rect
			(at 0 0 180)
			(size 0.762 0.889)
			(layers "B.Cu" "B.Mask" "B.Paste")
			(net "PVCCIN_CPU1")
		)
		(pad "2" smd rect
			(at 0 1.397 180)
			(size 0.762 0.889)
			(layers "B.Cu" "B.Mask" "B.Paste")
			(net "GND")
		)
		(zone
			(layer "B.Cu")
			(hatch none 0.5)
			(connect_pads
				(clearance 0)
			)
			(min_thickness 0.25)
			(keepout
				(tracks not_allowed)
				(vias allowed)
				(pads allowed)
				(copperpour not_allowed)
				(footprints allowed)
			)
			(placement
				(enabled no)
				(sheetname "")
			)
			(fill
				(thermal_gap 0.5)
				(thermal_bridge_width 0.5)
				(island_removal_mode 0)
			)
			(polygon
				(pts
					(xy 49.8094 -70.5485) (xy 49.0474 -70.5485) (xy 49.0474 -70.0405) (xy 49.8094 -70.0405)
				)
			)
		)
	)
	(footprint ""
		(layer "B.Cu")
		(at 420.624 -81.4705 180)
		(property "Reference" "C2P1"
			(at 0 0 0)
			(layer "B.SilkS")
			(hide yes)
			(effects
				(font
					(size 1.27 1.27)
				)
				(justify mirror)
			)
		)
		(property "Value" ""
			(at 0 0 0)
			(layer "B.Fab")
			(effects
				(font
					(size 1.27 1.27)
				)
				(justify mirror)
			)
		)
		(duplicate_pad_numbers_are_jumpers no)
		(fp_poly
			(pts
				(xy -0.3048 -0.1016) (xy -0.3048 0.9906) (xy 0.3048 0.9906) (xy 0.3048 -0.1016)
			)
			(stroke
				(width 0)
				(type default)
			)
			(fill no)
			(layer "B.CrtYd")
		)
		(fp_line
			(start 0.3048 0.9906)
			(end -0.3048 0.9906)
			(stroke
				(width 0.1)
				(type default)
			)
			(layer "B.Fab")
		)
		(fp_line
			(start 0.3048 -0.1016)
			(end 0.3048 0.9906)
			(stroke
				(width 0.1)
				(type default)
			)
			(layer "B.Fab")
		)
		(fp_line
			(start -0.3048 0.9906)
			(end -0.3048 -0.1016)
			(stroke
				(width 0.1)
				(type default)
			)
			(layer "B.Fab")
		)
		(fp_line
			(start -0.3048 -0.1016)
			(end 0.3048 -0.1016)
			(stroke
				(width 0.1)
				(type default)
			)
			(layer "B.Fab")
		)
		(pad "1" smd rect
			(at 0 0)
			(size 0.508 0.508)
			(layers "B.Cu" "B.Mask" "B.Paste")
			(net "P3V3_STBY")
		)
		(pad "2" smd rect
			(at 0 0.889)
			(size 0.508 0.508)
			(layers "B.Cu" "B.Mask" "B.Paste")
			(net "GND")
		)
		(zone
			(layer "B.Cu")
			(hatch none 0.5)
			(connect_pads
				(clearance 0)
			)
			(min_thickness 0.25)
			(keepout
				(tracks not_allowed)
				(vias allowed)
				(pads allowed)
				(copperpour not_allowed)
				(footprints allowed)
			)
			(placement
				(enabled no)
				(sheetname "")
			)
			(fill
				(thermal_gap 0.5)
				(thermal_bridge_width 0.5)
				(island_removal_mode 0)
			)
			(polygon
				(pts
					(xy 420.37 -82.1055) (xy 420.878 -82.1055) (xy 420.878 -81.7245) (xy 420.37 -81.7245)
				)
			)
		)
		(zone
			(layer "B.Cu")
			(hatch none 0.5)
			(connect_pads
				(clearance 0)
			)
			(min_thickness 0.25)
			(keepout
				(tracks allowed)
				(vias not_allowed)
				(pads allowed)
				(copperpour not_allowed)
				(footprints allowed)
			)
			(placement
				(enabled no)
				(sheetname "")
			)
			(fill
				(thermal_gap 0.5)
				(thermal_bridge_width 0.5)
				(island_removal_mode 0)
			)
			(polygon
				(pts
					(xy 420.37 -81.7245) (xy 420.878 -81.7245) (xy 420.878 -82.1055) (xy 420.37 -82.1055)
				)
			)
		)
	)
	(footprint ""
		(layer "B.Cu")
		(at 420.624 -155.829 90)
		(property "Reference" "C2L3"
			(at 0 0 90)
			(layer "B.SilkS")
			(hide yes)
			(effects
				(font
					(size 1.27 1.27)
				)
				(justify mirror)
			)
		)
		(property "Value" ""
			(at 0 0 90)
			(layer "B.Fab")
			(effects
				(font
					(size 1.27 1.27)
				)
				(justify mirror)
			)
		)
		(duplicate_pad_numbers_are_jumpers no)
		(fp_poly
			(pts
				(xy -0.3048 -0.1016) (xy -0.3048 0.9906) (xy 0.3048 0.9906) (xy 0.3048 -0.1016)
			)
			(stroke
				(width 0)
				(type default)
			)
			(fill no)
			(layer "B.CrtYd")
		)
		(fp_line
			(start 0.3048 -0.1016)
			(end 0.3048 0.9906)
			(stroke
				(width 0.1)
				(type default)
			)
			(layer "B.Fab")
		)
		(fp_line
			(start -0.3048 -0.1016)
			(end 0.3048 -0.1016)
			(stroke
				(width 0.1)
				(type default)
			)
			(layer "B.Fab")
		)
		(fp_line
			(start 0.3048 0.9906)
			(end -0.3048 0.9906)
			(stroke
				(width 0.1)
				(type default)
			)
			(layer "B.Fab")
		)
		(fp_line
			(start -0.3048 0.9906)
			(end -0.3048 -0.1016)
			(stroke
				(width 0.1)
				(type default)
			)
			(layer "B.Fab")
		)
		(pad "1" smd rect
			(at 0 0 270)
			(size 0.508 0.508)
			(layers "B.Cu" "B.Mask" "B.Paste")
			(net "SATA6G_PCH_PCIE_UP_SATA_RXN<3>")
		)
		(pad "2" smd rect
			(at 0 0.889 270)
			(size 0.508 0.508)
			(layers "B.Cu" "B.Mask" "B.Paste")
			(net "SATA6G_P3_RX_C_DN")
		)
		(zone
			(layer "B.Cu")
			(hatch none 0.5)
			(connect_pads
				(clearance 0)
			)
			(min_thickness 0.25)
			(keepout
				(tracks allowed)
				(vias not_allowed)
				(pads allowed)
				(copperpour not_allowed)
				(footprints allowed)
			)
			(placement
				(enabled no)
				(sheetname "")
			)
			(fill
				(thermal_gap 0.5)
				(thermal_bridge_width 0.5)
				(island_removal_mode 0)
			)
			(polygon
				(pts
					(xy 420.878 -156.083) (xy 420.878 -155.575) (xy 421.259 -155.575) (xy 421.259 -156.083)
				)
			)
		)
		(zone
			(layer "B.Cu")
			(hatch none 0.5)
			(connect_pads
				(clearance 0)
			)
			(min_thickness 0.25)
			(keepout
				(tracks not_allowed)
				(vias allowed)
				(pads allowed)
				(copperpour not_allowed)
				(footprints allowed)
			)
			(placement
				(enabled no)
				(sheetname "")
			)
			(fill
				(thermal_gap 0.5)
				(thermal_bridge_width 0.5)
				(island_removal_mode 0)
			)
			(polygon
				(pts
					(xy 421.259 -156.083) (xy 421.259 -155.575) (xy 420.878 -155.575) (xy 420.878 -156.083)
				)
			)
		)
	)
)
